(kicad_pcb
	(version 20260206)
	(generator "pcbnew")
	(generator_version "10.0")
	(general
		(thickness 1.6)
		(legacy_teardrops no)
	)
	(paper "A4")
	(title_block
		(title "01162023_DA0F0TEBIF0_F0T_Expander_BD_F_brd_V02_OCP.brd")
		(comment 1 "Grand Teton / footprints 3190-3196 of 9728")
	)
	(layers
		(0 "F.Cu" signal "TOP")
		(4 "In1.Cu" signal "GND")
		(6 "In2.Cu" signal "VCC")
		(8 "In3.Cu" signal "VCC1")
		(10 "In4.Cu" signal "GND1")
		(12 "In5.Cu" signal "IN1")
		(14 "In6.Cu" signal "GND2")
		(16 "In7.Cu" signal "IN2")
		(18 "In8.Cu" signal "GND3")
		(20 "In9.Cu" signal "IN3")
		(22 "In10.Cu" signal "GND4")
		(24 "In11.Cu" signal "IN4")
		(26 "In12.Cu" signal "GND5")
		(28 "In13.Cu" signal "IN5")
		(30 "In14.Cu" signal "GND6")
		(32 "In15.Cu" signal "IN6")
		(34 "In16.Cu" signal "GND7")
		(2 "B.Cu" signal "BOTTOM")
		(9 "F.Adhes" user "F.Adhesive")
		(11 "B.Adhes" user "B.Adhesive")
		(13 "F.Paste" user "Package Geometry/Pastemask Top")
		(15 "B.Paste" user "Package Geometry/Pastemask Bottom")
		(5 "F.SilkS" user "Ref Des/Silkscreen Top")
		(7 "B.SilkS" user "Ref Des/Silkscreen Bottom")
		(1 "F.Mask" user "Board Geometry/Soldermask Top")
		(3 "B.Mask" user "Board Geometry/Soldermask Bottom")
		(17 "Dwgs.User" user "User.Drawings")
		(19 "Cmts.User" user "User.Comments")
		(21 "Eco1.User" user "User.Eco1")
		(23 "Eco2.User" user "User.Eco2")
		(25 "Edge.Cuts" user "Board Geometry/Outline")
		(27 "Margin" user)
		(31 "F.CrtYd" user "Package Geometry/Place Bound Top")
		(29 "B.CrtYd" user "Package Geometry/Place Bound Bottom")
		(35 "F.Fab" user "Ref Des/Assembly Top")
		(33 "B.Fab" user "Ref Des/Assembly Bottom")
	)
	(footprint ""
		(layer "F.Cu")
		(at 241.076988 -296.764202 -90)
		(property "Reference" "PL22"
			(at -3.521202 -7.653528 90)
			(unlocked yes)
			(layer "F.SilkS")
			(effects
				(font
					(size 0.7874 0.5842)
					(thickness 0.1524)
				)
				(justify left)
			)
		)
		(property "Value" ""
			(at 0 0 270)
			(layer "F.Fab")
			(effects
				(font
					(size 1.27 1.27)
				)
			)
		)
		(duplicate_pad_numbers_are_jumpers no)
		(fp_line
			(start -6.849872 6.450076)
			(end -6.849872 1.9812)
			(stroke
				(width 0.1524)
				(type default)
			)
			(layer "F.SilkS")
		)
		(fp_line
			(start 6.849872 6.450076)
			(end -6.849872 6.450076)
			(stroke
				(width 0.1524)
				(type default)
			)
			(layer "F.SilkS")
		)
		(fp_line
			(start 6.849872 1.9812)
			(end 6.849872 6.450076)
			(stroke
				(width 0.1524)
				(type default)
			)
			(layer "F.SilkS")
		)
		(fp_line
			(start -6.849872 -1.9812)
			(end -6.849872 -6.450076)
			(stroke
				(width 0.1524)
				(type default)
			)
			(layer "F.SilkS")
		)
		(fp_line
			(start -6.849872 -6.450076)
			(end 6.849872 -6.450076)
			(stroke
				(width 0.1524)
				(type default)
			)
			(layer "F.SilkS")
		)
		(fp_line
			(start 6.849872 -6.450076)
			(end 6.849872 -1.9812)
			(stroke
				(width 0.1524)
				(type default)
			)
			(layer "F.SilkS")
		)
		(fp_line
			(start -6.849872 6.450076)
			(end -6.849872 -6.450076)
			(stroke
				(width 0.1)
				(type default)
			)
			(layer "F.Fab")
		)
		(fp_line
			(start 6.849872 6.450076)
			(end -6.849872 6.450076)
			(stroke
				(width 0.1)
				(type default)
			)
			(layer "F.Fab")
		)
		(fp_line
			(start -6.849872 -6.450076)
			(end 6.849872 -6.450076)
			(stroke
				(width 0.1)
				(type default)
			)
			(layer "F.Fab")
		)
		(fp_line
			(start 6.849872 -6.450076)
			(end 6.849872 6.450076)
			(stroke
				(width 0.1)
				(type default)
			)
			(layer "F.Fab")
		)
		(pad "1" smd rect
			(at -5.407406 0 270)
			(size 2.9464 3.7084)
			(layers "F.Cu" "F.Mask" "F.Paste")
			(net "SW_P1V25_PEX2_PH")
		)
		(pad "2" smd rect
			(at 5.407406 0 270)
			(size 2.9464 3.7084)
			(layers "F.Cu" "F.Mask" "F.Paste")
			(net "P1V25_PEX2_R")
		)
	)
	(footprint ""
		(layer "F.Cu")
		(at 407.4033 -59.571636 90)
		(property "Reference" "PR282"
			(at 0 0 90)
			(layer "F.SilkS")
			(hide yes)
			(effects
				(font
					(size 1.27 1.27)
				)
			)
		)
		(property "Value" ""
			(at 0 0 90)
			(layer "F.Fab")
			(effects
				(font
					(size 1.27 1.27)
				)
			)
		)
		(duplicate_pad_numbers_are_jumpers no)
		(fp_line
			(start 0.7874 -0.4064)
			(end 0.7874 0.4064)
			(stroke
				(width 0.1524)
				(type default)
			)
			(layer "F.SilkS")
		)
		(fp_line
			(start -0.7874 -0.4064)
			(end 0.7874 -0.4064)
			(stroke
				(width 0.1524)
				(type default)
			)
			(layer "F.SilkS")
		)
		(fp_line
			(start 0.7874 0.4064)
			(end -0.7874 0.4064)
			(stroke
				(width 0.1524)
				(type default)
			)
			(layer "F.SilkS")
		)
		(fp_line
			(start -0.7874 0.4064)
			(end -0.7874 -0.4064)
			(stroke
				(width 0.1524)
				(type default)
			)
			(layer "F.SilkS")
		)
		(fp_line
			(start -0.12065 -0.305054)
			(end -0.12065 -0.2794)
			(stroke
				(width 0.1)
				(type default)
			)
			(layer "F.Fab")
		)
		(fp_line
			(start -0.67945 -0.305054)
			(end -0.12065 -0.305054)
			(stroke
				(width 0.1)
				(type default)
			)
			(layer "F.Fab")
		)
		(fp_line
			(start 0.67945 -0.3048)
			(end 0.67945 0.3048)
			(stroke
				(width 0.1)
				(type default)
			)
			(layer "F.Fab")
		)
		(fp_line
			(start 0.12065 -0.3048)
			(end 0.67945 -0.3048)
			(stroke
				(width 0.1)
				(type default)
			)
			(layer "F.Fab")
		)
		(fp_line
			(start 0.12065 -0.2794)
			(end 0.12065 -0.3048)
			(stroke
				(width 0.1)
				(type default)
			)
			(layer "F.Fab")
		)
		(fp_line
			(start -0.12065 -0.2794)
			(end 0.12065 -0.2794)
			(stroke
				(width 0.1)
				(type default)
			)
			(layer "F.Fab")
		)
		(fp_line
			(start 0.120396 0.2794)
			(end -0.12065 0.2794)
			(stroke
				(width 0.1)
				(type default)
			)
			(layer "F.Fab")
		)
		(fp_line
			(start -0.12065 0.2794)
			(end -0.12065 0.3048)
			(stroke
				(width 0.1)
				(type default)
			)
			(layer "F.Fab")
		)
		(fp_line
			(start 0.67945 0.3048)
			(end 0.120396 0.3048)
			(stroke
				(width 0.1)
				(type default)
			)
			(layer "F.Fab")
		)
		(fp_line
			(start 0.120396 0.3048)
			(end 0.120396 0.2794)
			(stroke
				(width 0.1)
				(type default)
			)
			(layer "F.Fab")
		)
		(fp_line
			(start -0.12065 0.3048)
			(end -0.67945 0.3048)
			(stroke
				(width 0.1)
				(type default)
			)
			(layer "F.Fab")
		)
		(fp_line
			(start -0.67945 0.3048)
			(end -0.67945 -0.305054)
			(stroke
				(width 0.1)
				(type default)
			)
			(layer "F.Fab")
		)
		(pad "1" smd circle
			(at -0.40005 0 90)
			(size 0 0)
			(layers "F.Cu" "F.Mask" "F.Paste")
			(net "P3V3_SSD14_OCP")
		)
		(pad "2" smd circle
			(at 0.40005 0 90)
			(size 0 0)
			(layers "F.Cu" "F.Mask" "F.Paste")
			(net "GND")
		)
	)
	(footprint ""
		(layer "F.Cu")
		(at 359.156 -178.054)
		(property "Reference" "R4663"
			(at 0 0 0)
			(layer "F.SilkS")
			(hide yes)
			(effects
				(font
					(size 1.27 1.27)
				)
			)
		)
		(property "Value" ""
			(at 0 0 0)
			(layer "F.Fab")
			(effects
				(font
					(size 1.27 1.27)
				)
			)
		)
		(duplicate_pad_numbers_are_jumpers no)
		(fp_line
			(start -0.7874 -0.4064)
			(end 0.7874 -0.4064)
			(stroke
				(width 0.1524)
				(type default)
			)
			(layer "F.SilkS")
		)
		(fp_line
			(start -0.7874 0.4064)
			(end -0.7874 -0.4064)
			(stroke
				(width 0.1524)
				(type default)
			)
			(layer "F.SilkS")
		)
		(fp_line
			(start 0.7874 -0.4064)
			(end 0.7874 0.4064)
			(stroke
				(width 0.1524)
				(type default)
			)
			(layer "F.SilkS")
		)
		(fp_line
			(start 0.7874 0.4064)
			(end -0.7874 0.4064)
			(stroke
				(width 0.1524)
				(type default)
			)
			(layer "F.SilkS")
		)
		(fp_line
			(start -0.67945 -0.305054)
			(end -0.12065 -0.305054)
			(stroke
				(width 0.1)
				(type default)
			)
			(layer "F.Fab")
		)
		(fp_line
			(start -0.67945 0.3048)
			(end -0.67945 -0.305054)
			(stroke
				(width 0.1)
				(type default)
			)
			(layer "F.Fab")
		)
		(fp_line
			(start -0.12065 -0.305054)
			(end -0.12065 -0.2794)
			(stroke
				(width 0.1)
				(type default)
			)
			(layer "F.Fab")
		)
		(fp_line
			(start -0.12065 -0.2794)
			(end 0.12065 -0.2794)
			(stroke
				(width 0.1)
				(type default)
			)
			(layer "F.Fab")
		)
		(fp_line
			(start -0.12065 0.2794)
			(end -0.12065 0.3048)
			(stroke
				(width 0.1)
				(type default)
			)
			(layer "F.Fab")
		)
		(fp_line
			(start -0.12065 0.3048)
			(end -0.67945 0.3048)
			(stroke
				(width 0.1)
				(type default)
			)
			(layer "F.Fab")
		)
		(fp_line
			(start 0.120396 0.2794)
			(end -0.12065 0.2794)
			(stroke
				(width 0.1)
				(type default)
			)
			(layer "F.Fab")
		)
		(fp_line
			(start 0.120396 0.3048)
			(end 0.120396 0.2794)
			(stroke
				(width 0.1)
				(type default)
			)
			(layer "F.Fab")
		)
		(fp_line
			(start 0.12065 -0.3048)
			(end 0.67945 -0.3048)
			(stroke
				(width 0.1)
				(type default)
			)
			(layer "F.Fab")
		)
		(fp_line
			(start 0.12065 -0.2794)
			(end 0.12065 -0.3048)
			(stroke
				(width 0.1)
				(type default)
			)
			(layer "F.Fab")
		)
		(fp_line
			(start 0.67945 -0.3048)
			(end 0.67945 0.3048)
			(stroke
				(width 0.1)
				(type default)
			)
			(layer "F.Fab")
		)
		(fp_line
			(start 0.67945 0.3048)
			(end 0.120396 0.3048)
			(stroke
				(width 0.1)
				(type default)
			)
			(layer "F.Fab")
		)
		(pad "1" smd circle
			(at -0.40005 0)
			(size 0 0)
			(layers "F.Cu" "F.Mask" "F.Paste")
			(net "P3V3_AUX")
		)
		(pad "2" smd circle
			(at 0.40005 0)
			(size 0 0)
			(layers "F.Cu" "F.Mask" "F.Paste")
			(net "SSD6_PEX_PWR_EN_R")
		)
	)
	(footprint ""
		(layer "F.Cu")
		(at 363.474 -202.819 180)
		(property "Reference" "R4683"
			(at 0 0 180)
			(layer "F.SilkS")
			(hide yes)
			(effects
				(font
					(size 1.27 1.27)
				)
			)
		)
		(property "Value" ""
			(at 0 0 180)
			(layer "F.Fab")
			(effects
				(font
					(size 1.27 1.27)
				)
			)
		)
		(duplicate_pad_numbers_are_jumpers no)
		(fp_line
			(start 0.7874 0.4064)
			(end -0.7874 0.4064)
			(stroke
				(width 0.1524)
				(type default)
			)
			(layer "F.SilkS")
		)
		(fp_line
			(start 0.7874 -0.4064)
			(end 0.7874 0.4064)
			(stroke
				(width 0.1524)
				(type default)
			)
			(layer "F.SilkS")
		)
		(fp_line
			(start -0.7874 0.4064)
			(end -0.7874 -0.4064)
			(stroke
				(width 0.1524)
				(type default)
			)
			(layer "F.SilkS")
		)
		(fp_line
			(start -0.7874 -0.4064)
			(end 0.7874 -0.4064)
			(stroke
				(width 0.1524)
				(type default)
			)
			(layer "F.SilkS")
		)
		(fp_line
			(start 0.67945 0.3048)
			(end 0.120396 0.3048)
			(stroke
				(width 0.1)
				(type default)
			)
			(layer "F.Fab")
		)
		(fp_line
			(start 0.67945 -0.3048)
			(end 0.67945 0.3048)
			(stroke
				(width 0.1)
				(type default)
			)
			(layer "F.Fab")
		)
		(fp_line
			(start 0.12065 -0.2794)
			(end 0.12065 -0.3048)
			(stroke
				(width 0.1)
				(type default)
			)
			(layer "F.Fab")
		)
		(fp_line
			(start 0.12065 -0.3048)
			(end 0.67945 -0.3048)
			(stroke
				(width 0.1)
				(type default)
			)
			(layer "F.Fab")
		)
		(fp_line
			(start 0.120396 0.3048)
			(end 0.120396 0.2794)
			(stroke
				(width 0.1)
				(type default)
			)
			(layer "F.Fab")
		)
		(fp_line
			(start 0.120396 0.2794)
			(end -0.12065 0.2794)
			(stroke
				(width 0.1)
				(type default)
			)
			(layer "F.Fab")
		)
		(fp_line
			(start -0.12065 0.3048)
			(end -0.67945 0.3048)
			(stroke
				(width 0.1)
				(type default)
			)
			(layer "F.Fab")
		)
		(fp_line
			(start -0.12065 0.2794)
			(end -0.12065 0.3048)
			(stroke
				(width 0.1)
				(type default)
			)
			(layer "F.Fab")
		)
		(fp_line
			(start -0.12065 -0.2794)
			(end 0.12065 -0.2794)
			(stroke
				(width 0.1)
				(type default)
			)
			(layer "F.Fab")
		)
		(fp_line
			(start -0.12065 -0.305054)
			(end -0.12065 -0.2794)
			(stroke
				(width 0.1)
				(type default)
			)
			(layer "F.Fab")
		)
		(fp_line
			(start -0.67945 0.3048)
			(end -0.67945 -0.305054)
			(stroke
				(width 0.1)
				(type default)
			)
			(layer "F.Fab")
		)
		(fp_line
			(start -0.67945 -0.305054)
			(end -0.12065 -0.305054)
			(stroke
				(width 0.1)
				(type default)
			)
			(layer "F.Fab")
		)
		(pad "1" smd circle
			(at -0.40005 0 180)
			(size 0 0)
			(layers "F.Cu" "F.Mask" "F.Paste")
			(net "PCA9555_0_PEX1_A1")
		)
		(pad "2" smd circle
			(at 0.40005 0 180)
			(size 0 0)
			(layers "F.Cu" "F.Mask" "F.Paste")
			(net "P3V3_AUX")
		)
	)
	(footprint ""
		(layer "F.Cu")
		(at 107.02925 -105.253536)
		(property "Reference" "PD77"
			(at 1.17475 2.791206 0)
			(unlocked yes)
			(layer "F.SilkS")
			(effects
				(font
					(size 0.7874 0.5842)
					(thickness 0.1524)
				)
				(justify left)
			)
		)
		(property "Value" ""
			(at 0 0 0)
			(layer "F.Fab")
			(effects
				(font
					(size 1.27 1.27)
				)
			)
		)
		(duplicate_pad_numbers_are_jumpers no)
		(fp_line
			(start -3.656584 -1.970024)
			(end -3.656584 1.970024)
			(stroke
				(width 0.1524)
				(type default)
			)
			(layer "F.SilkS")
		)
		(fp_line
			(start -3.656584 1.970024)
			(end 4.240784 1.970024)
			(stroke
				(width 0.1524)
				(type default)
			)
			(layer "F.SilkS")
		)
		(fp_line
			(start 4.240784 -1.970024)
			(end -3.656584 -1.970024)
			(stroke
				(width 0.1524)
				(type default)
			)
			(layer "F.SilkS")
		)
		(fp_line
			(start 4.240784 1.970024)
			(end 4.240784 -1.970024)
			(stroke
				(width 0.1524)
				(type default)
			)
			(layer "F.SilkS")
		)
		(fp_rect
			(start 3.580384 1.970024)
			(end 4.240784 -1.970024)
			(stroke
				(width 0)
				(type default)
			)
			(fill yes)
			(layer "F.SilkS")
		)
		(fp_line
			(start -2.3749 -1.970024)
			(end -2.3749 1.970024)
			(stroke
				(width 0.1)
				(type default)
			)
			(layer "F.Fab")
		)
		(fp_line
			(start -2.3749 1.970024)
			(end 2.3749 1.970024)
			(stroke
				(width 0.1)
				(type default)
			)
			(layer "F.Fab")
		)
		(fp_line
			(start 2.3749 -1.970024)
			(end -2.3749 -1.970024)
			(stroke
				(width 0.1)
				(type default)
			)
			(layer "F.Fab")
		)
		(fp_line
			(start 2.3749 1.970024)
			(end 2.3749 -1.970024)
			(stroke
				(width 0.1)
				(type default)
			)
			(layer "F.Fab")
		)
		(fp_text user "+"
			(at -4.9784 -0.23495 0)
			(unlocked yes)
			(layer "F.Fab")
			(effects
				(font
					(size 1.905 1.4224)
					(thickness 0.1524)
				)
				(justify left)
			)
		)
		(fp_text user "-"
			(at 4.1656 -0.23495 0)
			(unlocked yes)
			(layer "F.Fab")
			(effects
				(font
					(size 1.905 1.4224)
					(thickness 0.1524)
				)
				(justify left)
			)
		)
		(pad "A" smd rect
			(at -2.450084 0)
			(size 2.159 2.2606)
			(layers "F.Cu" "F.Mask" "F.Paste")
			(net "GND")
		)
		(pad "C" smd rect
			(at 2.450084 0)
			(size 2.159 2.2606)
			(layers "F.Cu" "F.Mask" "F.Paste")
			(net "P12V_AUX")
		)
	)
	(footprint ""
		(layer "F.Cu")
		(at 176.220628 -26.666444 -90)
		(property "Reference" "R4065"
			(at 0 0 270)
			(layer "F.SilkS")
			(hide yes)
			(effects
				(font
					(size 1.27 1.27)
				)
			)
		)
		(property "Value" ""
			(at 0 0 270)
			(layer "F.Fab")
			(effects
				(font
					(size 1.27 1.27)
				)
			)
		)
		(duplicate_pad_numbers_are_jumpers no)
		(fp_line
			(start -0.7874 0.4064)
			(end -0.7874 -0.4064)
			(stroke
				(width 0.1524)
				(type default)
			)
			(layer "F.SilkS")
		)
		(fp_line
			(start 0.7874 0.4064)
			(end -0.7874 0.4064)
			(stroke
				(width 0.1524)
				(type default)
			)
			(layer "F.SilkS")
		)
		(fp_line
			(start -0.7874 -0.4064)
			(end 0.7874 -0.4064)
			(stroke
				(width 0.1524)
				(type default)
			)
			(layer "F.SilkS")
		)
		(fp_line
			(start 0.7874 -0.4064)
			(end 0.7874 0.4064)
			(stroke
				(width 0.1524)
				(type default)
			)
			(layer "F.SilkS")
		)
		(fp_line
			(start -0.67945 0.3048)
			(end -0.67945 -0.305054)
			(stroke
				(width 0.1)
				(type default)
			)
			(layer "F.Fab")
		)
		(fp_line
			(start -0.12065 0.3048)
			(end -0.67945 0.3048)
			(stroke
				(width 0.1)
				(type default)
			)
			(layer "F.Fab")
		)
		(fp_line
			(start 0.120396 0.3048)
			(end 0.120396 0.2794)
			(stroke
				(width 0.1)
				(type default)
			)
			(layer "F.Fab")
		)
		(fp_line
			(start 0.67945 0.3048)
			(end 0.120396 0.3048)
			(stroke
				(width 0.1)
				(type default)
			)
			(layer "F.Fab")
		)
		(fp_line
			(start -0.12065 0.2794)
			(end -0.12065 0.3048)
			(stroke
				(width 0.1)
				(type default)
			)
			(layer "F.Fab")
		)
		(fp_line
			(start 0.120396 0.2794)
			(end -0.12065 0.2794)
			(stroke
				(width 0.1)
				(type default)
			)
			(layer "F.Fab")
		)
		(fp_line
			(start -0.12065 -0.2794)
			(end 0.12065 -0.2794)
			(stroke
				(width 0.1)
				(type default)
			)
			(layer "F.Fab")
		)
		(fp_line
			(start 0.12065 -0.2794)
			(end 0.12065 -0.3048)
			(stroke
				(width 0.1)
				(type default)
			)
			(layer "F.Fab")
		)
		(fp_line
			(start 0.12065 -0.3048)
			(end 0.67945 -0.3048)
			(stroke
				(width 0.1)
				(type default)
			)
			(layer "F.Fab")
		)
		(fp_line
			(start 0.67945 -0.3048)
			(end 0.67945 0.3048)
			(stroke
				(width 0.1)
				(type default)
			)
			(layer "F.Fab")
		)
		(fp_line
			(start -0.67945 -0.305054)
			(end -0.12065 -0.305054)
			(stroke
				(width 0.1)
				(type default)
			)
			(layer "F.Fab")
		)
		(fp_line
			(start -0.12065 -0.305054)
			(end -0.12065 -0.2794)
			(stroke
				(width 0.1)
				(type default)
			)
			(layer "F.Fab")
		)
		(pad "1" smd circle
			(at -0.40005 0 270)
			(size 0 0)
			(layers "F.Cu" "F.Mask" "F.Paste")
			(net "PRSNT_SSD6_R_N")
		)
		(pad "2" smd circle
			(at 0.40005 0 270)
			(size 0 0)
			(layers "F.Cu" "F.Mask" "F.Paste")
			(net "PRSNT_SSD6_N")
		)
	)
	(footprint ""
		(layer "F.Cu")
		(at 25.964896 -17.999964)
		(property "Reference" "H71"
			(at -4.208018 -5.095748 0)
			(unlocked yes)
			(layer "F.SilkS")
			(effects
				(font
					(size 0.7874 0.5842)
					(thickness 0.1524)
				)
				(justify left)
			)
		)
		(property "Value" ""
			(at 0 0 0)
			(layer "F.Fab")
			(effects
				(font
					(size 1.27 1.27)
				)
			)
		)
		(duplicate_pad_numbers_are_jumpers no)
		(pad "1" thru_hole circle
			(at 0 0)
			(size 10.0076 10.0076)
			(drill 5.6134)
			(layers "*.Cu" "*.Mask")
			(remove_unused_layers no)
			(net "GND")
			(clearance -1.9431)
		)
	)
)
